FILE_TYPE = CONNECTIVITY;
{Allegro Design Entry HDL 17.2-2016 S081 (4005846) 1/11/2022}
"PAGE_NUMBER" = 99;
0"NC";
1"M_C_CPU1_SA_CB<7:0>";
2"M_C_CPU1_SA_CA<6:0>";
3"M_C_CPU1_SB_CA<6:0>";
4"M_C_CPU1_SB_CB<7:0>";
5"M_C_CPU1_SA_DQ<31:0>";
6"M_C_CPU1_SB_DQ<31:0>";
7"M_C_CPU1_SA_DQS_DN<9:0>";
8"M_C_CPU1_SA_DQS_DP<9:0>";
9"M_C_CPU1_SB_DQS_DN<9:0>";
10"M_C_CPU1_SB_DQS_DP<9:0>";
11"GND\g";
12"GND\g";
13"P3V3_STBY\g";
14"I3C_SPD_DDRAF_CPU1_SCL";
15"I3C_SPD_DDRC_CPU1_SCL";
16"PWRGD_CHC_CPU1_DIMM";
17"I3C_SPD_DDRAF_CPU1_SDA";
18"TP_CHC_CPU1_DIMM_RFU_4";
19"TP_CHC_CPU1_DIMM_RFU_5";
20"TP_CHC_CPU1_DIMM_RFU_6";
21"PD_CHC_CPU1_DIMM_SAA";
22"P3V3_STBY\g";
23"PWRGD_CHAF_CPU1";
24"P12V_MEM_2\g";
25"GND\g";
26"GND\g";
27"GND\g";
28"M_C_CPU1_SB_DQS_DP<9>";
29"M_C_CPU1_SB_DQS_DN<9>";
30"M_C_CPU1_SA_DQS_DP<9>";
31"M_C_CPU1_SA_DQS_DN<9>";
32"M_C_CPU1_SA_DQS_DP<8>";
33"M_C_CPU1_SA_DQS_DN<8>";
34"M_C_CPU1_SB_DQS_DN<7>";
35"M_C_CPU1_SA_DQS_DP<7>";
36"M_C_CPU1_SB_DQS_DP<6>";
37"M_C_CPU1_SB_DQS_DN<6>";
38"M_C_CPU1_SA_DQS_DN<6>";
39"M_C_CPU1_SB_DQS_DP<5>";
40"M_C_CPU1_SB_DQS_DN<5>";
41"M_C_CPU1_SA_DQS_DP<5>";
42"M_C_CPU1_SA_DQS_DN<5>";
43"M_C_CPU1_SB_DQS_DP<4>";
44"M_C_CPU1_SB_DQS_DN<4>";
45"M_C_CPU1_SA_DQS_DP<4>";
46"M_C_CPU1_SA_DQS_DN<4>";
47"M_C_CPU1_SB_DQS_DP<3>";
48"M_C_CPU1_SB_DQS_DN<3>";
49"M_C_CPU1_SA_DQS_DP<3>";
50"M_C_CPU1_SA_DQS_DN<3>";
51"M_C_CPU1_SB_DQS_DP<2>";
52"M_C_CPU1_SB_DQS_DN<2>";
53"M_C_CPU1_SA_DQS_DP<2>";
54"M_C_CPU1_SA_DQS_DN<2>";
55"M_C_CPU1_SB_DQS_DP<1>";
56"M_C_CPU1_SB_DQS_DN<1>";
57"M_C_CPU1_SA_DQS_DP<1>";
58"M_C_CPU1_SA_DQS_DN<1>";
59"M_C_CPU1_SB_DQS_DP<0>";
60"M_C_CPU1_SB_DQS_DN<0>";
61"M_C_CPU1_SA_DQS_DP<0>";
62"M_C_CPU1_SA_DQS_DN<0>";
63"M_C_CPU1_SB_DQS_DP<7>";
64"M_C_CPU1_SB_DQS_DN<8>";
65"M_C_CPU1_SB_DQS_DP<8>";
66"M_C_CPU1_SA_DQS_DP<6>";
67"M_C_CPU1_SA_DQS_DN<7>";
68"TP_CHC_CPU1_DIMM_RFU_0";
69"TP_CHC_CPU1_DIMM_RFU_1";
70"TP_CHC_CPU1_DIMM_RFU_2";
71"TP_CHC_CPU1_DIMM_RFU_3";
72"M_C_CPU1_RESET_N";
73"M_C_CPU1_SB_PAR";
74"M_C_CPU1_SA_PAR";
75"M_C_CPU1_SB_RSP<0>";
76"M_C_CPU1_SA_RSP<0>";
77"M_C_CPU1_SB_DQ<0>";
78"M_C_CPU1_SB_DQ<1>";
79"M_C_CPU1_SB_DQ<2>";
80"M_C_CPU1_SB_DQ<3>";
81"M_C_CPU1_SB_DQ<4>";
82"M_C_CPU1_SB_DQ<5>";
83"M_C_CPU1_SB_DQ<6>";
84"M_C_CPU1_SB_DQ<7>";
85"M_C_CPU1_SB_DQ<8>";
86"M_C_CPU1_SB_DQ<9>";
87"M_C_CPU1_SB_DQ<10>";
88"M_C_CPU1_SB_DQ<11>";
89"M_C_CPU1_SB_DQ<12>";
90"M_C_CPU1_SB_DQ<13>";
91"M_C_CPU1_SB_DQ<14>";
92"M_C_CPU1_SB_DQ<15>";
93"M_C_CPU1_SB_DQ<16>";
94"M_C_CPU1_SB_DQ<17>";
95"M_C_CPU1_SB_DQ<18>";
96"M_C_CPU1_SB_DQ<19>";
97"M_C_CPU1_SB_DQ<20>";
98"M_C_CPU1_SB_DQ<21>";
99"M_C_CPU1_SB_DQ<22>";
100"M_C_CPU1_SB_DQ<23>";
101"M_C_CPU1_SB_DQ<24>";
102"M_C_CPU1_SB_DQ<25>";
103"M_C_CPU1_SB_DQ<26>";
104"M_C_CPU1_SB_DQ<27>";
105"M_C_CPU1_SB_DQ<28>";
106"M_C_CPU1_SB_DQ<29>";
107"M_C_CPU1_SB_DQ<30>";
108"M_C_CPU1_SB_DQ<31>";
109"M_C_CPU1_SA_DQ<0>";
110"M_C_CPU1_SA_DQ<1>";
111"M_C_CPU1_SA_DQ<2>";
112"M_C_CPU1_SA_DQ<3>";
113"M_C_CPU1_SA_DQ<4>";
114"M_C_CPU1_SA_DQ<5>";
115"M_C_CPU1_SA_DQ<6>";
116"M_C_CPU1_SA_DQ<7>";
117"M_C_CPU1_SA_DQ<8>";
118"M_C_CPU1_SA_DQ<9>";
119"M_C_CPU1_SA_DQ<10>";
120"M_C_CPU1_SA_DQ<11>";
121"M_C_CPU1_SA_DQ<12>";
122"M_C_CPU1_SA_DQ<13>";
123"M_C_CPU1_SA_DQ<14>";
124"M_C_CPU1_SA_DQ<15>";
125"M_C_CPU1_SA_DQ<16>";
126"M_C_CPU1_SA_DQ<17>";
127"M_C_CPU1_SA_DQ<18>";
128"M_C_CPU1_SA_DQ<19>";
129"M_C_CPU1_SA_DQ<20>";
130"M_C_CPU1_SA_DQ<21>";
131"M_C_CPU1_SA_DQ<22>";
132"M_C_CPU1_SA_DQ<23>";
133"M_C_CPU1_SA_DQ<24>";
134"M_C_CPU1_SA_DQ<25>";
135"M_C_CPU1_SA_DQ<26>";
136"M_C_CPU1_SA_DQ<27>";
137"M_C_CPU1_SA_DQ<28>";
138"M_C_CPU1_SA_DQ<29>";
139"M_C_CPU1_SA_DQ<30>";
140"M_C_CPU1_SB_CS_N<1>";
141"M_C_CPU1_SA_CS_N<1>";
142"M_C_CPU1_SB_CS_N<0>";
143"M_C_CPU1_SA_CS_N<0>";
144"M_C_CPU1_CLK_DP<0>";
145"M_C_CPU1_CLK_DN<0>";
146"M_C_CPU1_SB_CB<0>";
147"M_C_CPU1_SB_CB<1>";
148"M_C_CPU1_SB_CB<2>";
149"M_C_CPU1_SB_CB<3>";
150"M_C_CPU1_SB_CB<4>";
151"M_C_CPU1_SB_CB<5>";
152"M_C_CPU1_SB_CB<6>";
153"M_C_CPU1_SA_CB<0>";
154"M_C_CPU1_SA_CB<2>";
155"M_C_CPU1_SA_CB<3>";
156"M_C_CPU1_SA_CB<5>";
157"M_C_CPU1_SA_CB<6>";
158"M_C_CPU1_SB_CA<6>";
159"M_C_CPU1_SA_CA<6>";
160"M_C_CPU1_SB_CA<5>";
161"M_C_CPU1_SA_CA<5>";
162"M_C_CPU1_SB_CA<4>";
163"M_C_CPU1_SA_CA<4>";
164"M_C_CPU1_SB_CA<3>";
165"M_C_CPU1_SA_CA<3>";
166"M_C_CPU1_SB_CA<2>";
167"M_C_CPU1_SA_CA<2>";
168"M_C_CPU1_SB_CA<1>";
169"M_C_CPU1_SA_CA<1>";
170"M_C_CPU1_SB_CA<0>";
171"M_C_CPU1_SA_CA<0>";
172"M_C_CPU1_ALERT_N";
173"M_C_CPU1_SB_CB<7>";
174"M_C_CPU1_SA_CB<1>";
175"M_C_CPU1_SA_CB<4>";
176"M_C_CPU1_SA_CB<7>";
177"M_C_CPU1_SA_DQ<31>";
178"PD_CHC_CPU1_DIMM_SAA";
%"TAP"
"1","(-6200,4000)","0","mstr_standard","I100";
;
CDS_LIB"mstr_standard"
BODY_TYPE"PLUMBING"
HDL_TAP"TRUE";
"B \NAC \NWC"5;
"S \NAC"
BN"3"112;
%"TAP"
"1","(-6200,4050)","0","mstr_standard","I101";
;
CDS_LIB"mstr_standard"
BODY_TYPE"PLUMBING"
HDL_TAP"TRUE";
"B \NAC \NWC"5;
"S \NAC"
BN"4"113;
%"TAP"
"1","(-6200,4100)","0","mstr_standard","I102";
;
CDS_LIB"mstr_standard"
BODY_TYPE"PLUMBING"
HDL_TAP"TRUE";
"B \NAC \NWC"5;
"S \NAC"
BN"5"114;
%"TAP"
"1","(-6200,4150)","0","mstr_standard","I103";
;
CDS_LIB"mstr_standard"
BODY_TYPE"PLUMBING"
HDL_TAP"TRUE";
"B \NAC \NWC"5;
"S \NAC"
BN"6"115;
%"TAP"
"1","(-6200,4200)","0","mstr_standard","I104";
;
CDS_LIB"mstr_standard"
BODY_TYPE"PLUMBING"
HDL_TAP"TRUE";
"B \NAC \NWC"5;
"S \NAC"
BN"7"116;
%"TAP"
"1","(-6200,4300)","0","mstr_standard","I105";
;
CDS_LIB"mstr_standard"
BODY_TYPE"PLUMBING"
HDL_TAP"TRUE";
"B \NAC \NWC"5;
"S \NAC"
BN"9"118;
%"TAP"
"1","(-6200,4350)","0","mstr_standard","I106";
;
CDS_LIB"mstr_standard"
BODY_TYPE"PLUMBING"
HDL_TAP"TRUE";
"B \NAC \NWC"5;
"S \NAC"
BN"10"119;
%"TAP"
"1","(-6200,4250)","0","mstr_standard","I107";
;
CDS_LIB"mstr_standard"
BODY_TYPE"PLUMBING"
HDL_TAP"TRUE";
"B \NAC \NWC"5;
"S \NAC"
BN"8"117;
%"TAP"
"1","(-6200,4400)","0","mstr_standard","I108";
;
CDS_LIB"mstr_standard"
BODY_TYPE"PLUMBING"
HDL_TAP"TRUE";
"B \NAC \NWC"5;
"S \NAC"
BN"11"120;
%"TAP"
"1","(-6200,4450)","0","mstr_standard","I109";
;
CDS_LIB"mstr_standard"
BODY_TYPE"PLUMBING"
HDL_TAP"TRUE";
"B \NAC \NWC"5;
"S \NAC"
BN"12"121;
%"TAP"
"1","(-6200,4550)","0","mstr_standard","I110";
;
CDS_LIB"mstr_standard"
BODY_TYPE"PLUMBING"
HDL_TAP"TRUE";
"B \NAC \NWC"5;
"S \NAC"
BN"14"123;
%"TAP"
"1","(-6200,4600)","0","mstr_standard","I111";
;
CDS_LIB"mstr_standard"
BODY_TYPE"PLUMBING"
HDL_TAP"TRUE";
"B \NAC \NWC"5;
"S \NAC"
BN"15"124;
%"TAP"
"1","(-6200,4500)","0","mstr_standard","I112";
;
CDS_LIB"mstr_standard"
BODY_TYPE"PLUMBING"
HDL_TAP"TRUE";
"B \NAC \NWC"5;
"S \NAC"
BN"13"122;
%"TAP"
"1","(-6200,4650)","0","mstr_standard","I113";
;
CDS_LIB"mstr_standard"
BODY_TYPE"PLUMBING"
HDL_TAP"TRUE";
"B \NAC \NWC"5;
"S \NAC"
BN"16"125;
%"TAP"
"1","(-6200,4700)","0","mstr_standard","I114";
;
CDS_LIB"mstr_standard"
BODY_TYPE"PLUMBING"
HDL_TAP"TRUE";
"B \NAC \NWC"5;
"S \NAC"
BN"17"126;
%"TAP"
"1","(-6200,4850)","0","mstr_standard","I115";
;
CDS_LIB"mstr_standard"
BODY_TYPE"PLUMBING"
HDL_TAP"TRUE";
"B \NAC \NWC"5;
"S \NAC"
BN"20"129;
%"TAP"
"1","(-6200,4800)","0","mstr_standard","I116";
;
CDS_LIB"mstr_standard"
BODY_TYPE"PLUMBING"
HDL_TAP"TRUE";
"B \NAC \NWC"5;
"S \NAC"
BN"19"128;
%"TAP"
"1","(-6200,4750)","0","mstr_standard","I117";
;
CDS_LIB"mstr_standard"
BODY_TYPE"PLUMBING"
HDL_TAP"TRUE";
"B \NAC \NWC"5;
"S \NAC"
BN"18"127;
%"TAP"
"1","(-6200,4900)","0","mstr_standard","I118";
;
CDS_LIB"mstr_standard"
BODY_TYPE"PLUMBING"
HDL_TAP"TRUE";
"B \NAC \NWC"5;
"S \NAC"
BN"21"130;
%"TAP"
"1","(-6200,4950)","0","mstr_standard","I119";
;
CDS_LIB"mstr_standard"
BODY_TYPE"PLUMBING"
HDL_TAP"TRUE";
"B \NAC \NWC"5;
"S \NAC"
BN"22"131;
%"TAP"
"1","(-6200,5000)","0","mstr_standard","I120";
;
CDS_LIB"mstr_standard"
BODY_TYPE"PLUMBING"
HDL_TAP"TRUE";
"B \NAC \NWC"5;
"S \NAC"
BN"23"132;
%"TAP"
"1","(-6200,5050)","0","mstr_standard","I121";
;
CDS_LIB"mstr_standard"
BODY_TYPE"PLUMBING"
HDL_TAP"TRUE";
"B \NAC \NWC"5;
"S \NAC"
BN"24"133;
%"TAP"
"1","(-6200,5100)","0","mstr_standard","I122";
;
CDS_LIB"mstr_standard"
BODY_TYPE"PLUMBING"
HDL_TAP"TRUE";
"B \NAC \NWC"5;
"S \NAC"
BN"25"134;
%"TAP"
"1","(-6200,5250)","0","mstr_standard","I123";
;
CDS_LIB"mstr_standard"
BODY_TYPE"PLUMBING"
HDL_TAP"TRUE";
"B \NAC \NWC"5;
"S \NAC"
BN"28"137;
%"TAP"
"1","(-6200,5200)","0","mstr_standard","I124";
;
CDS_LIB"mstr_standard"
BODY_TYPE"PLUMBING"
HDL_TAP"TRUE";
"B \NAC \NWC"5;
"S \NAC"
BN"27"136;
%"TAP"
"1","(-6200,5150)","0","mstr_standard","I125";
;
CDS_LIB"mstr_standard"
BODY_TYPE"PLUMBING"
HDL_TAP"TRUE";
"B \NAC \NWC"5;
"S \NAC"
BN"26"135;
%"TAP"
"1","(-6200,5300)","0","mstr_standard","I126";
;
CDS_LIB"mstr_standard"
BODY_TYPE"PLUMBING"
HDL_TAP"TRUE";
"B \NAC \NWC"5;
"S \NAC"
BN"29"138;
%"TAP"
"1","(-6200,5350)","0","mstr_standard","I127";
;
CDS_LIB"mstr_standard"
BODY_TYPE"PLUMBING"
HDL_TAP"TRUE";
"B \NAC \NWC"5;
"S \NAC"
BN"30"139;
%"TAP"
"1","(-6200,5400)","0","mstr_standard","I128";
;
CDS_LIB"mstr_standard"
BODY_TYPE"PLUMBING"
HDL_TAP"TRUE";
"B \NAC \NWC"5;
"S \NAC"
BN"31"177;
%"GND"
"1","(-6600,1025)","0","mstr_symbols","I147";
;
SIZE"1B"
BOM_COST"MEM"
CDS_LIB"mstr_symbols"
BODY_TYPE"PLUMBING"
VOLTAGE"0.0"
HDL_POWER"GND";
"A\NAC"11;
%"Q_RES"
"2","(-6600,1250)","0","pure_quanta","I148";
;
LOCATION"R771"
$SEC"1"
CDS_SEC"1"
WATTAGE"1/16W"
MATERIAL"CHIP"
TOLERANCE"1%"
VALUE"23.2K"
PART_NUMBER"TMP_QCS32322FB11"
PACK_TYPE"0402LF"
CDS_LIB"pure_quanta";
"A"
$PN"1"178;
"B"
$PN"2"11;
%"GND"
"1","(-2225,2000)","0","mstr_symbols","I154";
;
SIZE"1B"
CDS_LIB"mstr_symbols"
BODY_TYPE"PLUMBING"
VOLTAGE"0.0"
HDL_POWER"GND";
"A\NAC"27;
%"SCONN288_DDR506112002KQ"
"3","(-1325,3750)","0","pure_quanta","I155";
;
LOCATION"J28"
$SEC"3"
CDS_SEC"3"
MATERIAL"IO"
PART_TYPE"SMLF"
VALUE"SCONN288_DDR506112002KQ"
PART_NUMBER"DFHST8FS479"
CDS_LMAN_SYM_OUTLINE"-450,1800,450,-1750"
NEEDS_NO_SIZE"TRUE"
CDS_LIB"pure_quanta";
"G3"
$PN"G3"26;
"G2"
$PN"G2"26;
"G1"
$PN"G1"26;
"VSS62"
$PN"141"26;
"VSS61"
$PN"139"26;
"VSS60"
$PN"136"26;
"VSS58"
$PN"132"26;
"VSS104"
$PN"240"27;
"VSS102"
$PN"235"27;
"VSS100"
$PN"230"27;
"VIN_BULK2"
$PN"146"24;
"VIN_BULK1"
$PN"145"24;
"VIN_BULK0"
$PN"1"24;
"VSS126"
$PN"288"27;
"VSS125"
$PN"286"27;
"VSS124"
$PN"284"27;
"VSS123"
$PN"281"27;
"VSS122"
$PN"279"27;
"VSS121"
$PN"277"27;
"VSS120"
$PN"275"27;
"VSS119"
$PN"273"27;
"VSS118"
$PN"270"27;
"VSS117"
$PN"268"27;
"VSS116"
$PN"266"27;
"VSS115"
$PN"264"27;
"VSS114"
$PN"262"27;
"VSS113"
$PN"259"27;
"VSS112"
$PN"257"27;
"VSS111"
$PN"255"27;
"VSS110"
$PN"253"27;
"VSS109"
$PN"251"27;
"VSS108"
$PN"248"27;
"VSS107"
$PN"246"27;
"VSS106"
$PN"244"27;
"VSS105"
$PN"242"27;
"VSS103"
$PN"237"27;
"VSS101"
$PN"233"27;
"VSS99"
$PN"228"27;
"VSS98"
$PN"226"27;
"VSS97"
$PN"224"27;
"VSS96"
$PN"222"27;
"VSS95"
$PN"219"27;
"VSS94"
$PN"216"27;
"VSS93"
$PN"214"27;
"VSS92"
$PN"212"27;
"VSS91"
$PN"210"27;
"VSS90"
$PN"208"27;
"VSS89"
$PN"206"27;
"VSS88"
$PN"204"27;
"VSS87"
$PN"202"27;
"VSS86"
$PN"199"27;
"VSS85"
$PN"197"27;
"VSS84"
$PN"195"27;
"VSS83"
$PN"193"27;
"VSS82"
$PN"191"27;
"VSS81"
$PN"188"27;
"VSS80"
$PN"186"27;
"VSS79"
$PN"184"27;
"VSS78"
$PN"182"27;
"VSS77"
$PN"180"27;
"VSS76"
$PN"177"27;
"VSS75"
$PN"175"27;
"VSS74"
$PN"173"27;
"VSS73"
$PN"171"27;
"VSS72"
$PN"169"27;
"VSS71"
$PN"166"27;
"VSS70"
$PN"164"27;
"VSS69"
$PN"162"27;
"VSS68"
$PN"160"27;
"VSS67"
$PN"158"27;
"VSS66"
$PN"155"27;
"VSS65"
$PN"153"27;
"VSS64"
$PN"151"27;
"VSS63"
$PN"143"26;
"VSS59"
$PN"134"26;
"VSS57"
$PN"130"26;
"VSS56"
$PN"128"26;
"VSS55"
$PN"125"26;
"VSS54"
$PN"123"26;
"VSS53"
$PN"121"26;
"VSS52"
$PN"119"26;
"VSS51"
$PN"117"26;
"VSS50"
$PN"114"26;
"VSS49"
$PN"112"26;
"VSS48"
$PN"110"26;
"VSS47"
$PN"108"26;
"VSS46"
$PN"106"26;
"VSS45"
$PN"103"26;
"VSS44"
$PN"101"26;
"VSS43"
$PN"99"26;
"VSS42"
$PN"97"26;
"VSS41"
$PN"95"26;
"VSS40"
$PN"92"26;
"VSS39"
$PN"90"26;
"VSS38"
$PN"88"26;
"VSS37"
$PN"85"26;
"VSS36"
$PN"83"26;
"VSS35"
$PN"81"26;
"VSS34"
$PN"79"26;
"VSS33"
$PN"77"26;
"VSS32"
$PN"75"26;
"VSS31"
$PN"73"26;
"VSS30"
$PN"71"26;
"VSS29"
$PN"69"26;
"VSS28"
$PN"67"26;
"VSS27"
$PN"65"26;
"VSS26"
$PN"63"26;
"VSS25"
$PN"61"26;
"VSS24"
$PN"59"26;
"VSS23"
$PN"57"26;
"VSS22"
$PN"54"26;
"VSS21"
$PN"52"26;
"VSS20"
$PN"50"26;
"VSS19"
$PN"48"26;
"VSS18"
$PN"46"26;
"VSS17"
$PN"43"26;
"VSS16"
$PN"41"26;
"VSS15"
$PN"39"26;
"VSS14"
$PN"37"26;
"VSS13"
$PN"35"26;
"VSS12"
$PN"32"26;
"VSS11"
$PN"30"26;
"VSS10"
$PN"28"26;
"VSS9"
$PN"26"26;
"VSS8"
$PN"24"26;
"VSS7"
$PN"21"26;
"VSS6"
$PN"19"26;
"VSS5"
$PN"17"26;
"VSS4"
$PN"15"26;
"VSS3"
$PN"13"26;
"VSS2"
$PN"10"26;
"VSS1"
$PN"8"26;
"VSS0"
$PN"6"26;
%"GND"
"1","(-425,1800)","0","mstr_symbols","I156";
;
SIZE"1B"
CDS_LIB"mstr_symbols"
BODY_TYPE"PLUMBING"
VOLTAGE"0.0"
HDL_POWER"GND";
"A\NAC"26;
%"Q_CAP"
"1","(-8775,3225)","2","pure_quanta","I185";
;
LOCATION"C144"
$SEC"1"
CDS_SEC"1"
MATERIAL"X7R"
TOLERANCE"10%"
VALUE"0.1UF"
PART_NUMBER"CH4104K1B00"
VOLTAGE"25V"
PACK_TYPE"0402"
BOM_COST"MEM"
CDS_LIB"pure_quanta"
ROOM"MEM_CH_A_CPU0_DIMM1";
"B"
$PN"2"12;
"A"
$PN"1"22;
%"GND"
"1","(-8775,3000)","0","mstr_symbols","I186";
;
BOM_COST"MEM"
SIZE"1B"
CDS_LIB"mstr_symbols"
BODY_TYPE"PLUMBING"
VOLTAGE"0"
ROOM"MEM_EFGH_DECOUPLING_CAPS"
HDL_POWER"GND";
"A\NAC"12;
%"Q_RES"
"1","(-8700,2150)","2","pure_quanta","I188";
;
LOCATION"R305"
$SEC"1"
CDS_SEC"1"
VALUE"0"
BOM_COST"MEM"
CDS_LIB"pure_quanta"
WATTAGE"1/16W"
MATERIAL"CHIP"
TOLERANCE"5%"
PART_NUMBER"CS00002JB38"
PACK_TYPE"0402LF"
ROOM"RST_CPU0_PLD_TO_DIMM";
"B"
$PN"2"23;
"A"
$PN"1"16;
%"VCC_CORE"
"1","(-8575,2475)","0","mstr_symbols","I189";
;
HDL_POWER"P3V3_STBY"
CDS_LIB"mstr_symbols"
VOLTAGE"3.3"
ROOM"PVCCINFAON_CPU0_CTRL";
"A"13;
%"Q_RES"
"2","(-8575,2300)","0","pure_quanta","I190";
;
LOCATION"R105"
$SEC"1"
CDS_SEC"1"
MATERIAL"EMPTY"
PACK_TYPE"0402LF"
WATTAGE"1/16W"
TOLERANCE"5%"
VALUE"1K"
CDS_LIB"pure_quanta"
BOM_COST"MEM"
PART_NUMBER"TMP_QCS21002JB34"
ROOM"MEM_CH_A_CPU0_DIMM1";
"A"
$PN"1"13;
"B"
$PN"2"16;
%"TAP"
"1","(-3550,3750)","0","mstr_standard","I191";
;
CDS_LIB"mstr_standard"
BODY_TYPE"PLUMBING"
HDL_TAP"TRUE";
"B \NAC \NWC"8;
"S \NAC"
BN"1"57;
%"TAP"
"1","(-3550,3850)","0","mstr_standard","I193";
;
CDS_LIB"mstr_standard"
BODY_TYPE"PLUMBING"
HDL_TAP"TRUE";
"B \NAC \NWC"8;
"S \NAC"
BN"2"53;
%"TAP"
"1","(-3350,4400)","0","mstr_standard","I196";
;
CDS_LIB"mstr_standard"
BODY_TYPE"PLUMBING"
HDL_TAP"TRUE";
"B \NAC \NWC"7;
"S \NAC"
BN"8"33;
%"TAP"
"1","(-3350,4500)","0","mstr_standard","I197";
;
CDS_LIB"mstr_standard"
BODY_TYPE"PLUMBING"
HDL_TAP"TRUE";
"B \NAC \NWC"7;
"S \NAC"
BN"9"31;
%"TAP"
"1","(-3550,4450)","0","mstr_standard","I198";
;
CDS_LIB"mstr_standard"
BODY_TYPE"PLUMBING"
HDL_TAP"TRUE";
"B \NAC \NWC"8;
"S \NAC"
BN"8"32;
%"TAP"
"1","(-3550,4550)","0","mstr_standard","I199";
;
CDS_LIB"mstr_standard"
BODY_TYPE"PLUMBING"
HDL_TAP"TRUE";
"B \NAC \NWC"8;
"S \NAC"
BN"9"30;
%"TAP"
"1","(-3550,4350)","0","mstr_standard","I200";
;
CDS_LIB"mstr_standard"
BODY_TYPE"PLUMBING"
HDL_TAP"TRUE";
"B \NAC \NWC"8;
"S \NAC"
BN"7"35;
%"TAP"
"1","(-3350,4100)","0","mstr_standard","I203";
;
CDS_LIB"mstr_standard"
BODY_TYPE"PLUMBING"
HDL_TAP"TRUE";
"B \NAC \NWC"7;
"S \NAC"
BN"5"42;
%"TAP"
"1","(-3350,4300)","0","mstr_standard","I204";
;
CDS_LIB"mstr_standard"
BODY_TYPE"PLUMBING"
HDL_TAP"TRUE";
"B \NAC \NWC"7;
"S \NAC"
BN"7"67;
%"TAP"
"1","(-3350,4200)","0","mstr_standard","I205";
;
CDS_LIB"mstr_standard"
BODY_TYPE"PLUMBING"
HDL_TAP"TRUE";
"B \NAC \NWC"7;
"S \NAC"
BN"6"38;
%"TAP"
"1","(-3550,4250)","0","mstr_standard","I206";
;
CDS_LIB"mstr_standard"
BODY_TYPE"PLUMBING"
HDL_TAP"TRUE";
"B \NAC \NWC"8;
"S \NAC"
BN"6"66;
%"TAP"
"1","(-3550,4150)","0","mstr_standard","I207";
;
CDS_LIB"mstr_standard"
BODY_TYPE"PLUMBING"
HDL_TAP"TRUE";
"B \NAC \NWC"8;
"S \NAC"
BN"5"41;
%"TAP"
"1","(-3350,3900)","0","mstr_standard","I208";
;
CDS_LIB"mstr_standard"
BODY_TYPE"PLUMBING"
HDL_TAP"TRUE";
"B \NAC \NWC"7;
"S \NAC"
BN"3"50;
%"TAP"
"1","(-3350,4000)","0","mstr_standard","I209";
;
CDS_LIB"mstr_standard"
BODY_TYPE"PLUMBING"
HDL_TAP"TRUE";
"B \NAC \NWC"7;
"S \NAC"
BN"4"46;
%"TAP"
"1","(-3550,4050)","0","mstr_standard","I210";
;
CDS_LIB"mstr_standard"
BODY_TYPE"PLUMBING"
HDL_TAP"TRUE";
"B \NAC \NWC"8;
"S \NAC"
BN"4"45;
%"TAP"
"1","(-3550,3950)","0","mstr_standard","I211";
;
CDS_LIB"mstr_standard"
BODY_TYPE"PLUMBING"
HDL_TAP"TRUE";
"B \NAC \NWC"8;
"S \NAC"
BN"3"49;
%"TAP"
"1","(-3350,3600)","0","mstr_standard","I212";
;
CDS_LIB"mstr_standard"
BODY_TYPE"PLUMBING"
HDL_TAP"TRUE";
"B \NAC \NWC"7;
"S \NAC"
BN"0"62;
%"TAP"
"1","(-3350,3800)","0","mstr_standard","I213";
;
CDS_LIB"mstr_standard"
BODY_TYPE"PLUMBING"
HDL_TAP"TRUE";
"B \NAC \NWC"7;
"S \NAC"
BN"2"54;
%"TAP"
"1","(-3350,3700)","0","mstr_standard","I214";
;
CDS_LIB"mstr_standard"
BODY_TYPE"PLUMBING"
HDL_TAP"TRUE";
"B \NAC \NWC"7;
"S \NAC"
BN"1"58;
%"TAP"
"1","(-3550,3650)","0","mstr_standard","I215";
;
CDS_LIB"mstr_standard"
BODY_TYPE"PLUMBING"
HDL_TAP"TRUE";
"B \NAC \NWC"8;
"S \NAC"
BN"0"61;
%"TAP"
"1","(-3350,3350)","0","mstr_standard","I216";
;
CDS_LIB"mstr_standard"
BODY_TYPE"PLUMBING"
HDL_TAP"TRUE";
"B \NAC \NWC"9;
"S \NAC"
BN"8"64;
%"TAP"
"1","(-3350,3450)","0","mstr_standard","I217";
;
CDS_LIB"mstr_standard"
BODY_TYPE"PLUMBING"
HDL_TAP"TRUE";
"B \NAC \NWC"9;
"S \NAC"
BN"9"29;
%"TAP"
"1","(-3550,3500)","0","mstr_standard","I218";
;
CDS_LIB"mstr_standard"
BODY_TYPE"PLUMBING"
HDL_TAP"TRUE";
"B \NAC \NWC"10;
"S \NAC"
BN"9"28;
%"TAP"
"1","(-3550,3400)","0","mstr_standard","I219";
;
CDS_LIB"mstr_standard"
BODY_TYPE"PLUMBING"
HDL_TAP"TRUE";
"B \NAC \NWC"10;
"S \NAC"
BN"8"65;
%"SCONN288_DDR506112002KQ"
"1","(-7050,3650)","0","pure_quanta","I22";
;
LOCATION"J28"
$SEC"1"
CDS_SEC"1"
PART_TYPE"SMLF"
PART_NUMBER"DFHST8FS479"
VALUE"SCONN288_DDR506112002KQ"
MATERIAL"IO"
CDS_LMAN_SYM_OUTLINE"-450,1900,450,-1850"
NEEDS_NO_SIZE"TRUE"
CDS_LIB"pure_quanta";
"PWR_GOOD||FAIL_N"
$PN"147"16;
"DQ31_A"
$PN"194"177;
"CB7_A"
$PN"205"176;
"CB4_A"
$PN"58"175;
"CB1_A"
$PN"53"174;
"CB7_B"
$PN"236"173;
"ALERT_N \B"
$PN"62"172;
"CA0_A"
$PN"66"171;
"CA0_B"
$PN"76"170;
"CA1_A"
$PN"211"169;
"CA1_B"
$PN"221"168;
"CA2_A"
$PN"68"167;
"CA2_B"
$PN"78"166;
"CA3_A"
$PN"213"165;
"CA3_B"
$PN"223"164;
"CA4_A"
$PN"70"163;
"CA4_B"
$PN"80"162;
"CA5_A"
$PN"215"161;
"CA5_B"
$PN"225"160;
"CA6_A"
$PN"72"159;
"CA6_B"
$PN"82"158;
"CB6_A"
$PN"203"157;
"CB5_A"
$PN"60"156;
"CB3_A"
$PN"198"155;
"CB2_A"
$PN"196"154;
"CB0_A"
$PN"51"153;
"CB6_B"
$PN"234"152;
"CB5_B"
$PN"91"151;
"CB4_B"
$PN"89"150;
"CB3_B"
$PN"243"149;
"CB2_B"
$PN"241"148;
"CB1_B"
$PN"98"147;
"CB0_B"
$PN"96"146;
"CK_C \B"
$PN"218"145;
"CK_T"
$PN"217"144;
"CS0_A_N"
$PN"64"143;
"CS0_B_N"
$PN"84"142;
"CS1_A_N"
$PN"209"141;
"CS1_B_N"
$PN"229"140;
"DQ30_A"
$PN"192"139;
"DQ29_A"
$PN"49"138;
"DQ28_A"
$PN"47"137;
"DQ27_A"
$PN"187"136;
"DQ26_A"
$PN"185"135;
"DQ25_A"
$PN"42"134;
"DQ24_A"
$PN"40"133;
"DQ23_A"
$PN"183"132;
"DQ22_A"
$PN"181"131;
"DQ21_A"
$PN"38"130;
"DQ20_A"
$PN"36"129;
"DQ19_A"
$PN"176"128;
"DQ18_A"
$PN"174"127;
"DQ17_A"
$PN"31"126;
"DQ16_A"
$PN"29"125;
"DQ15_A"
$PN"172"124;
"DQ14_A"
$PN"170"123;
"DQ13_A"
$PN"27"122;
"DQ12_A"
$PN"25"121;
"DQ11_A"
$PN"165"120;
"DQ10_A"
$PN"163"119;
"DQ9_A"
$PN"20"118;
"DQ8_A"
$PN"18"117;
"DQ7_A"
$PN"161"116;
"DQ6_A"
$PN"159"115;
"DQ5_A"
$PN"16"114;
"DQ4_A"
$PN"14"113;
"DQ3_A"
$PN"154"112;
"DQ2_A"
$PN"152"111;
"DQ1_A"
$PN"9"110;
"DQ0_A"
$PN"7"109;
"DQ31_B"
$PN"287"108;
"DQ30_B"
$PN"285"107;
"DQ29_B"
$PN"142"106;
"DQ28_B"
$PN"140"105;
"DQ27_B"
$PN"280"104;
"DQ26_B"
$PN"278"103;
"DQ25_B"
$PN"135"102;
"DQ24_B"
$PN"133"101;
"DQ23_B"
$PN"276"100;
"DQ22_B"
$PN"274"99;
"DQ21_B"
$PN"131"98;
"DQ20_B"
$PN"129"97;
"DQ19_B"
$PN"269"96;
"DQ18_B"
$PN"267"95;
"DQ17_B"
$PN"124"94;
"DQ16_B"
$PN"122"93;
"DQ15_B"
$PN"265"92;
"DQ14_B"
$PN"263"91;
"DQ13_B"
$PN"120"90;
"DQ12_B"
$PN"118"89;
"DQ11_B"
$PN"258"88;
"DQ10_B"
$PN"256"87;
"DQ9_B"
$PN"113"86;
"DQ8_B"
$PN"111"85;
"DQ7_B"
$PN"254"84;
"DQ6_B"
$PN"252"83;
"DQ5_B"
$PN"109"82;
"DQ4_B"
$PN"107"81;
"DQ3_B"
$PN"247"80;
"DQ2_B"
$PN"245"79;
"DQ1_B"
$PN"102"78;
"DQ0_B"
$PN"100"77;
"HAS"
$PN"148"21;
"HSCL"
$PN"4"15;
"HSDA"
$PN"5"17;
"LBD||RSP_A_N"
$PN"86"76;
"LBS||RSP_B_N"
$PN"87"75;
"PAR_A"
$PN"74"74;
"PAR_B"
$PN"227"73;
"RESET_N \B"
$PN"207"72;
"RFU6"
$PN"232"20;
"RFU5"
$PN"231"19;
"RFU4"
$PN"220"18;
"RFU3"
$PN"150"71;
"RFU2"
$PN"149"70;
"RFU1"
$PN"144"69;
"RFU0"
$PN"2"68;
"VIN_MGMT"
$PN"3"22;
%"TAP"
"1","(-3550,3300)","0","mstr_standard","I220";
;
CDS_LIB"mstr_standard"
BODY_TYPE"PLUMBING"
HDL_TAP"TRUE";
"B \NAC \NWC"10;
"S \NAC"
BN"7"63;
%"TAP"
"1","(-3350,3050)","0","mstr_standard","I221";
;
CDS_LIB"mstr_standard"
BODY_TYPE"PLUMBING"
HDL_TAP"TRUE";
"B \NAC \NWC"9;
"S \NAC"
BN"5"40;
%"TAP"
"1","(-3350,3250)","0","mstr_standard","I222";
;
CDS_LIB"mstr_standard"
BODY_TYPE"PLUMBING"
HDL_TAP"TRUE";
"B \NAC \NWC"9;
"S \NAC"
BN"7"34;
%"TAP"
"1","(-3350,3150)","0","mstr_standard","I223";
;
CDS_LIB"mstr_standard"
BODY_TYPE"PLUMBING"
HDL_TAP"TRUE";
"B \NAC \NWC"9;
"S \NAC"
BN"6"37;
%"TAP"
"1","(-3550,3200)","0","mstr_standard","I224";
;
CDS_LIB"mstr_standard"
BODY_TYPE"PLUMBING"
HDL_TAP"TRUE";
"B \NAC \NWC"10;
"S \NAC"
BN"6"36;
%"TAP"
"1","(-3550,3100)","0","mstr_standard","I225";
;
CDS_LIB"mstr_standard"
BODY_TYPE"PLUMBING"
HDL_TAP"TRUE";
"B \NAC \NWC"10;
"S \NAC"
BN"5"39;
%"TAP"
"1","(-3350,2950)","0","mstr_standard","I226";
;
CDS_LIB"mstr_standard"
BODY_TYPE"PLUMBING"
HDL_TAP"TRUE";
"B \NAC \NWC"9;
"S \NAC"
BN"4"44;
%"TAP"
"1","(-3350,2850)","0","mstr_standard","I227";
;
CDS_LIB"mstr_standard"
BODY_TYPE"PLUMBING"
HDL_TAP"TRUE";
"B \NAC \NWC"9;
"S \NAC"
BN"3"48;
%"TAP"
"1","(-3550,3000)","0","mstr_standard","I228";
;
CDS_LIB"mstr_standard"
BODY_TYPE"PLUMBING"
HDL_TAP"TRUE";
"B \NAC \NWC"10;
"S \NAC"
BN"4"43;
%"TAP"
"1","(-3550,2800)","0","mstr_standard","I229";
;
CDS_LIB"mstr_standard"
BODY_TYPE"PLUMBING"
HDL_TAP"TRUE";
"B \NAC \NWC"10;
"S \NAC"
BN"2"51;
%"TAP"
"1","(-7900,3200)","2","mstr_standard","I23";
;
CDS_LIB"mstr_standard"
BODY_TYPE"PLUMBING"
HDL_TAP"TRUE";
"B \NAC \NWC"4;
"S \NAC"
BN"0"146;
%"TAP"
"1","(-3550,2900)","0","mstr_standard","I230";
;
CDS_LIB"mstr_standard"
BODY_TYPE"PLUMBING"
HDL_TAP"TRUE";
"B \NAC \NWC"10;
"S \NAC"
BN"3"47;
%"TAP"
"1","(-3350,2550)","0","mstr_standard","I231";
;
CDS_LIB"mstr_standard"
BODY_TYPE"PLUMBING"
HDL_TAP"TRUE";
"B \NAC \NWC"9;
"S \NAC"
BN"0"60;
%"TAP"
"1","(-3350,2650)","0","mstr_standard","I232";
;
CDS_LIB"mstr_standard"
BODY_TYPE"PLUMBING"
HDL_TAP"TRUE";
"B \NAC \NWC"9;
"S \NAC"
BN"1"56;
%"TAP"
"1","(-3350,2750)","0","mstr_standard","I233";
;
CDS_LIB"mstr_standard"
BODY_TYPE"PLUMBING"
HDL_TAP"TRUE";
"B \NAC \NWC"9;
"S \NAC"
BN"2"52;
%"TAP"
"1","(-3550,2700)","0","mstr_standard","I234";
;
CDS_LIB"mstr_standard"
BODY_TYPE"PLUMBING"
HDL_TAP"TRUE";
"B \NAC \NWC"10;
"S \NAC"
BN"1"55;
%"TAP"
"1","(-3550,2600)","0","mstr_standard","I235";
;
CDS_LIB"mstr_standard"
BODY_TYPE"PLUMBING"
HDL_TAP"TRUE";
"B \NAC \NWC"10;
"S \NAC"
BN"0"59;
%"SCONN288_DDR506112002KQ"
"2","(-4500,3550)","0","pure_quanta","I236";
;
LOCATION"J28"
$SEC"2"
CDS_SEC"2"
PART_TYPE"SMLF"
MATERIAL"IO"
VALUE"SCONN288_DDR506112002KQ"
PART_NUMBER"DFHST8FS479"
CDS_LMAN_SYM_OUTLINE"-600,1150,600,-1150"
NEEDS_NO_SIZE"TRUE"
CDS_LIB"pure_quanta";
"DQS7_A_C||TDQS7_A_C \B"
$PN"178"67;
"DQS6_A_T||TDQS6_A_T"
$PN"168"66;
"DQS8_B_T||TDQS8_B_T"
$PN"283"65;
"DQS8_B_C||TDQS8_B_C \B"
$PN"282"64;
"DQS7_B_T||TDQS7_B_T"
$PN"272"63;
"DQS0_A_C \B"
$PN"12"62;
"DQS0_A_T"
$PN"11"61;
"DQS0_B_C \B"
$PN"105"60;
"DQS0_B_T"
$PN"104"59;
"DQS1_A_C \B"
$PN"23"58;
"DQS1_A_T"
$PN"22"57;
"DQS1_B_C \B"
$PN"116"56;
"DQS1_B_T"
$PN"115"55;
"DQS2_A_C \B"
$PN"34"54;
"DQS2_A_T"
$PN"33"53;
"DQS2_B_C \B"
$PN"127"52;
"DQS2_B_T"
$PN"126"51;
"DQS3_A_C \B"
$PN"45"50;
"DQS3_A_T"
$PN"44"49;
"DQS3_B_C \B"
$PN"138"48;
"DQS3_B_T"
$PN"137"47;
"DQS4_A_C \B"
$PN"56"46;
"DQS4_A_T"
$PN"55"45;
"DQS4_B_C \B"
$PN"238"44;
"DQS4_B_T"
$PN"239"43;
"DQS5_A_C||TDQS5_A_C||DQS5_A_T||TDQS5_A_T \B"
$PN"156"42;
"DQS5_A_T||TDQS5_A_T"
$PN"157"41;
"DQS5_B_C||TDQS5_B_C \B"
$PN"249"40;
"DQS5_B_T||TDQS5_B_T"
$PN"250"39;
"DQS6_A_C||TDQS6_A_C||DQS6_A_T||TDQS6_A_T \B"
$PN"167"38;
"DQS6_B_C||TDQS6_B_C \B"
$PN"260"37;
"DQS6_B_T||TDQS6_B_T"
$PN"261"36;
"DQS7_A_T||TDQS7_A_T"
$PN"179"35;
"DQS7_B_C||TDQS7_B_C \B"
$PN"271"34;
"DQS8_A_C||TDQS8_A_C \B"
$PN"189"33;
"DQS8_A_T||TDQS8_A_T"
$PN"190"32;
"DQS9_A_C||TDQS9_A_C \B"
$PN"200"31;
"DQS9_A_T||TDQS9_A_T"
$PN"201"30;
"DQS9_B_C||TDQS9_B_C \B"
$PN"94"29;
"DQS9_B_T||TDQS9_B_T||DBI4_B_N"
$PN"93"28;
%"GND"
"1","(-2925,5525)","0","pure_quanta_power","I237";
;
CDS_LIB"pure_quanta_power"
BOM_COST"MEM"
SIZE"1B"
ROOM"MEM_EFGH_DECOUPLING_CAPS"
HDL_POWER"GND";
"A<SIZE-1..0>\NAC"25;
%"Q_CAP"
"1","(-2925,5875)","2","pure_quanta","I238";
;
LOCATION"C178"
$SEC"1"
CDS_SEC"1"
MATERIAL"X6S"
TOLERANCE"10%"
VALUE"10UF"
PART_NUMBER"CH6104KEA00"
VOLTAGE"25V"
PACK_TYPE"C0805"
BOM_COST"MEM"
CDS_LIB"pure_quanta"
ROOM"MEM_CH_A_CPU0_DIMM1";
"B"
$PN"2"25;
"A"
$PN"1"24;
%"Q_CAP"
"1","(-2350,5875)","2","pure_quanta","I239";
;
LOCATION"C179"
$SEC"1"
CDS_SEC"1"
TOLERANCE"10%"
VALUE"10UF"
VOLTAGE"25V"
PACK_TYPE"C0805"
PART_NUMBER"CH6104KEA00"
MATERIAL"X6S"
BOM_COST"MEM"
CDS_LIB"pure_quanta"
ROOM"MEM_CH_A_CPU0_DIMM1";
"B"
$PN"2"25;
"A"
$PN"1"24;
%"TAP"
"1","(-7900,3300)","2","mstr_standard","I24";
;
CDS_LIB"mstr_standard"
BODY_TYPE"PLUMBING"
HDL_TAP"TRUE";
"B \NAC \NWC"4;
"S \NAC"
BN"2"148;
%"UNIVERSAL_POWER"
"1","(-2925,6200)","0","pure_quanta_power","I240";
;
HDL_POWER"P12V_MEM_2"
CDS_LIB"pure_quanta_power";
"A"24;
%"Q_RES"
"1","(-7950,2700)","0","pure_quanta","I242";
;
$LOCATION"R1582"
CDS_LOCATION"R1582"
$SEC"1"
CDS_SEC"1"
VALUE"49.9"
MATERIAL"CHIP"
PACK_TYPE"0402LF"
WATTAGE"1/16W"
TOLERANCE"1%"
PART_NUMBER"CS04992FB07"
CDS_LIB"pure_quanta";
"B"
$PN"2"15;
"A"
$PN"1"14;
%"TAP"
"1","(-7900,3250)","2","mstr_standard","I25";
;
CDS_LIB"mstr_standard"
BODY_TYPE"PLUMBING"
HDL_TAP"TRUE";
"B \NAC \NWC"4;
"S \NAC"
BN"1"147;
%"TAP"
"1","(-7900,3350)","2","mstr_standard","I26";
;
CDS_LIB"mstr_standard"
BODY_TYPE"PLUMBING"
HDL_TAP"TRUE";
"B \NAC \NWC"4;
"S \NAC"
BN"3"149;
%"TAP"
"1","(-7900,3400)","2","mstr_standard","I27";
;
CDS_LIB"mstr_standard"
BODY_TYPE"PLUMBING"
HDL_TAP"TRUE";
"B \NAC \NWC"4;
"S \NAC"
BN"4"150;
%"TAP"
"1","(-7900,3450)","2","mstr_standard","I28";
;
CDS_LIB"mstr_standard"
BODY_TYPE"PLUMBING"
HDL_TAP"TRUE";
"B \NAC \NWC"4;
"S \NAC"
BN"5"151;
%"TAP"
"1","(-7900,3550)","2","mstr_standard","I29";
;
CDS_LIB"mstr_standard"
BODY_TYPE"PLUMBING"
HDL_TAP"TRUE";
"B \NAC \NWC"4;
"S \NAC"
BN"7"173;
%"TAP"
"1","(-7900,3500)","2","mstr_standard","I30";
;
CDS_LIB"mstr_standard"
BODY_TYPE"PLUMBING"
HDL_TAP"TRUE";
"B \NAC \NWC"4;
"S \NAC"
BN"6"152;
%"TAP"
"1","(-7900,3650)","2","mstr_standard","I31";
;
CDS_LIB"mstr_standard"
BODY_TYPE"PLUMBING"
HDL_TAP"TRUE";
"B \NAC \NWC"1;
"S \NAC"
BN"0"153;
%"TAP"
"1","(-7900,3700)","2","mstr_standard","I32";
;
CDS_LIB"mstr_standard"
BODY_TYPE"PLUMBING"
HDL_TAP"TRUE";
"B \NAC \NWC"1;
"S \NAC"
BN"1"174;
%"TAP"
"1","(-7900,3750)","2","mstr_standard","I33";
;
CDS_LIB"mstr_standard"
BODY_TYPE"PLUMBING"
HDL_TAP"TRUE";
"B \NAC \NWC"1;
"S \NAC"
BN"2"154;
%"TAP"
"1","(-7900,3800)","2","mstr_standard","I34";
;
CDS_LIB"mstr_standard"
BODY_TYPE"PLUMBING"
HDL_TAP"TRUE";
"B \NAC \NWC"1;
"S \NAC"
BN"3"155;
%"TAP"
"1","(-6200,2250)","0","mstr_standard","I35";
;
CDS_LIB"mstr_standard"
BODY_TYPE"PLUMBING"
HDL_TAP"TRUE";
"B \NAC \NWC"6;
"S \NAC"
BN"1"78;
%"TAP"
"1","(-6200,2200)","0","mstr_standard","I36";
;
CDS_LIB"mstr_standard"
BODY_TYPE"PLUMBING"
HDL_TAP"TRUE";
"B \NAC \NWC"6;
"S \NAC"
BN"0"77;
%"TAP"
"1","(-6200,2300)","0","mstr_standard","I37";
;
CDS_LIB"mstr_standard"
BODY_TYPE"PLUMBING"
HDL_TAP"TRUE";
"B \NAC \NWC"6;
"S \NAC"
BN"2"79;
%"TAP"
"1","(-6200,2350)","0","mstr_standard","I38";
;
CDS_LIB"mstr_standard"
BODY_TYPE"PLUMBING"
HDL_TAP"TRUE";
"B \NAC \NWC"6;
"S \NAC"
BN"3"80;
%"TAP"
"1","(-6200,2400)","0","mstr_standard","I39";
;
CDS_LIB"mstr_standard"
BODY_TYPE"PLUMBING"
HDL_TAP"TRUE";
"B \NAC \NWC"6;
"S \NAC"
BN"4"81;
%"TAP"
"1","(-6200,2450)","0","mstr_standard","I40";
;
CDS_LIB"mstr_standard"
BODY_TYPE"PLUMBING"
HDL_TAP"TRUE";
"B \NAC \NWC"6;
"S \NAC"
BN"5"82;
%"TAP"
"1","(-6200,2550)","0","mstr_standard","I41";
;
CDS_LIB"mstr_standard"
BODY_TYPE"PLUMBING"
HDL_TAP"TRUE";
"B \NAC \NWC"6;
"S \NAC"
BN"7"84;
%"TAP"
"1","(-6200,2500)","0","mstr_standard","I42";
;
CDS_LIB"mstr_standard"
BODY_TYPE"PLUMBING"
HDL_TAP"TRUE";
"B \NAC \NWC"6;
"S \NAC"
BN"6"83;
%"TAP"
"1","(-6200,2650)","0","mstr_standard","I43";
;
CDS_LIB"mstr_standard"
BODY_TYPE"PLUMBING"
HDL_TAP"TRUE";
"B \NAC \NWC"6;
"S \NAC"
BN"9"86;
%"TAP"
"1","(-6200,2600)","0","mstr_standard","I44";
;
CDS_LIB"mstr_standard"
BODY_TYPE"PLUMBING"
HDL_TAP"TRUE";
"B \NAC \NWC"6;
"S \NAC"
BN"8"85;
%"TAP"
"1","(-6200,2750)","0","mstr_standard","I45";
;
CDS_LIB"mstr_standard"
BODY_TYPE"PLUMBING"
HDL_TAP"TRUE";
"B \NAC \NWC"6;
"S \NAC"
BN"11"88;
%"TAP"
"1","(-6200,2800)","0","mstr_standard","I46";
;
CDS_LIB"mstr_standard"
BODY_TYPE"PLUMBING"
HDL_TAP"TRUE";
"B \NAC \NWC"6;
"S \NAC"
BN"12"89;
%"TAP"
"1","(-6200,2700)","0","mstr_standard","I47";
;
CDS_LIB"mstr_standard"
BODY_TYPE"PLUMBING"
HDL_TAP"TRUE";
"B \NAC \NWC"6;
"S \NAC"
BN"10"87;
%"TAP"
"1","(-6200,2850)","0","mstr_standard","I48";
;
CDS_LIB"mstr_standard"
BODY_TYPE"PLUMBING"
HDL_TAP"TRUE";
"B \NAC \NWC"6;
"S \NAC"
BN"13"90;
%"TAP"
"1","(-6200,2900)","0","mstr_standard","I49";
;
CDS_LIB"mstr_standard"
BODY_TYPE"PLUMBING"
HDL_TAP"TRUE";
"B \NAC \NWC"6;
"S \NAC"
BN"14"91;
%"TAP"
"1","(-6200,2950)","0","mstr_standard","I50";
;
CDS_LIB"mstr_standard"
BODY_TYPE"PLUMBING"
HDL_TAP"TRUE";
"B \NAC \NWC"6;
"S \NAC"
BN"15"92;
%"TAP"
"1","(-6200,3050)","0","mstr_standard","I51";
;
CDS_LIB"mstr_standard"
BODY_TYPE"PLUMBING"
HDL_TAP"TRUE";
"B \NAC \NWC"6;
"S \NAC"
BN"17"94;
%"TAP"
"1","(-6200,3000)","0","mstr_standard","I52";
;
CDS_LIB"mstr_standard"
BODY_TYPE"PLUMBING"
HDL_TAP"TRUE";
"B \NAC \NWC"6;
"S \NAC"
BN"16"93;
%"TAP"
"1","(-6200,3100)","0","mstr_standard","I53";
;
CDS_LIB"mstr_standard"
BODY_TYPE"PLUMBING"
HDL_TAP"TRUE";
"B \NAC \NWC"6;
"S \NAC"
BN"18"95;
%"TAP"
"1","(-6200,3150)","0","mstr_standard","I54";
;
CDS_LIB"mstr_standard"
BODY_TYPE"PLUMBING"
HDL_TAP"TRUE";
"B \NAC \NWC"6;
"S \NAC"
BN"19"96;
%"TAP"
"1","(-6200,3200)","0","mstr_standard","I55";
;
CDS_LIB"mstr_standard"
BODY_TYPE"PLUMBING"
HDL_TAP"TRUE";
"B \NAC \NWC"6;
"S \NAC"
BN"20"97;
%"TAP"
"1","(-6200,3300)","0","mstr_standard","I56";
;
CDS_LIB"mstr_standard"
BODY_TYPE"PLUMBING"
HDL_TAP"TRUE";
"B \NAC \NWC"6;
"S \NAC"
BN"22"99;
%"TAP"
"1","(-6200,3250)","0","mstr_standard","I57";
;
CDS_LIB"mstr_standard"
BODY_TYPE"PLUMBING"
HDL_TAP"TRUE";
"B \NAC \NWC"6;
"S \NAC"
BN"21"98;
%"TAP"
"1","(-6200,3350)","0","mstr_standard","I58";
;
CDS_LIB"mstr_standard"
BODY_TYPE"PLUMBING"
HDL_TAP"TRUE";
"B \NAC \NWC"6;
"S \NAC"
BN"23"100;
%"TAP"
"1","(-6200,3450)","0","mstr_standard","I59";
;
CDS_LIB"mstr_standard"
BODY_TYPE"PLUMBING"
HDL_TAP"TRUE";
"B \NAC \NWC"6;
"S \NAC"
BN"25"102;
%"VCC_CORE"
"1","(-8675,3425)","0","mstr_symbols","I6";
;
HDL_POWER"P3V3_STBY"
CDS_LIB"mstr_symbols"
VOLTAGE"3.3"
ROOM"PVCCINFAON_CPU1_CTRL";
"A"22;
%"TAP"
"1","(-6200,3400)","0","mstr_standard","I60";
;
CDS_LIB"mstr_standard"
BODY_TYPE"PLUMBING"
HDL_TAP"TRUE";
"B \NAC \NWC"6;
"S \NAC"
BN"24"101;
%"TAP"
"1","(-6200,3500)","0","mstr_standard","I61";
;
CDS_LIB"mstr_standard"
BODY_TYPE"PLUMBING"
HDL_TAP"TRUE";
"B \NAC \NWC"6;
"S \NAC"
BN"26"103;
%"TAP"
"1","(-6200,3550)","0","mstr_standard","I62";
;
CDS_LIB"mstr_standard"
BODY_TYPE"PLUMBING"
HDL_TAP"TRUE";
"B \NAC \NWC"6;
"S \NAC"
BN"27"104;
%"TAP"
"1","(-6200,3650)","0","mstr_standard","I63";
;
CDS_LIB"mstr_standard"
BODY_TYPE"PLUMBING"
HDL_TAP"TRUE";
"B \NAC \NWC"6;
"S \NAC"
BN"29"106;
%"TAP"
"1","(-6200,3700)","0","mstr_standard","I64";
;
CDS_LIB"mstr_standard"
BODY_TYPE"PLUMBING"
HDL_TAP"TRUE";
"B \NAC \NWC"6;
"S \NAC"
BN"30"107;
%"TAP"
"1","(-6200,3600)","0","mstr_standard","I65";
;
CDS_LIB"mstr_standard"
BODY_TYPE"PLUMBING"
HDL_TAP"TRUE";
"B \NAC \NWC"6;
"S \NAC"
BN"28"105;
%"TAP"
"1","(-6200,3750)","0","mstr_standard","I66";
;
CDS_LIB"mstr_standard"
BODY_TYPE"PLUMBING"
HDL_TAP"TRUE";
"B \NAC \NWC"6;
"S \NAC"
BN"31"108;
%"TAP"
"1","(-7900,3850)","2","mstr_standard","I79";
;
CDS_LIB"mstr_standard"
BODY_TYPE"PLUMBING"
HDL_TAP"TRUE";
"B \NAC \NWC"1;
"S \NAC"
BN"4"175;
%"TAP"
"1","(-7900,3900)","2","mstr_standard","I80";
;
CDS_LIB"mstr_standard"
BODY_TYPE"PLUMBING"
HDL_TAP"TRUE";
"B \NAC \NWC"1;
"S \NAC"
BN"5"156;
%"TAP"
"1","(-7900,3950)","2","mstr_standard","I81";
;
CDS_LIB"mstr_standard"
BODY_TYPE"PLUMBING"
HDL_TAP"TRUE";
"B \NAC \NWC"1;
"S \NAC"
BN"6"157;
%"TAP"
"1","(-7900,4000)","2","mstr_standard","I82";
;
CDS_LIB"mstr_standard"
BODY_TYPE"PLUMBING"
HDL_TAP"TRUE";
"B \NAC \NWC"1;
"S \NAC"
BN"7"176;
%"TAP"
"1","(-7900,4700)","2","mstr_standard","I83";
;
CDS_LIB"mstr_standard"
BODY_TYPE"PLUMBING"
HDL_TAP"TRUE";
"B \NAC \NWC"3;
"S \NAC"
BN"0"170;
%"TAP"
"1","(-7900,4800)","2","mstr_standard","I84";
;
CDS_LIB"mstr_standard"
BODY_TYPE"PLUMBING"
HDL_TAP"TRUE";
"B \NAC \NWC"3;
"S \NAC"
BN"2"166;
%"TAP"
"1","(-7900,4750)","2","mstr_standard","I85";
;
CDS_LIB"mstr_standard"
BODY_TYPE"PLUMBING"
HDL_TAP"TRUE";
"B \NAC \NWC"3;
"S \NAC"
BN"1"168;
%"TAP"
"1","(-7900,4850)","2","mstr_standard","I86";
;
CDS_LIB"mstr_standard"
BODY_TYPE"PLUMBING"
HDL_TAP"TRUE";
"B \NAC \NWC"3;
"S \NAC"
BN"3"164;
%"TAP"
"1","(-7900,4900)","2","mstr_standard","I87";
;
CDS_LIB"mstr_standard"
BODY_TYPE"PLUMBING"
HDL_TAP"TRUE";
"B \NAC \NWC"3;
"S \NAC"
BN"4"162;
%"TAP"
"1","(-7900,4950)","2","mstr_standard","I88";
;
CDS_LIB"mstr_standard"
BODY_TYPE"PLUMBING"
HDL_TAP"TRUE";
"B \NAC \NWC"3;
"S \NAC"
BN"5"160;
%"TAP"
"1","(-7900,5000)","2","mstr_standard","I89";
;
CDS_LIB"mstr_standard"
BODY_TYPE"PLUMBING"
HDL_TAP"TRUE";
"B \NAC \NWC"3;
"S \NAC"
BN"6"158;
%"TAP"
"1","(-7900,5100)","2","mstr_standard","I90";
;
CDS_LIB"mstr_standard"
BODY_TYPE"PLUMBING"
HDL_TAP"TRUE";
"B \NAC \NWC"2;
"S \NAC"
BN"0"171;
%"TAP"
"1","(-7900,5150)","2","mstr_standard","I91";
;
CDS_LIB"mstr_standard"
BODY_TYPE"PLUMBING"
HDL_TAP"TRUE";
"B \NAC \NWC"2;
"S \NAC"
BN"1"169;
%"TAP"
"1","(-7900,5200)","2","mstr_standard","I92";
;
CDS_LIB"mstr_standard"
BODY_TYPE"PLUMBING"
HDL_TAP"TRUE";
"B \NAC \NWC"2;
"S \NAC"
BN"2"167;
%"TAP"
"1","(-7900,5250)","2","mstr_standard","I93";
;
CDS_LIB"mstr_standard"
BODY_TYPE"PLUMBING"
HDL_TAP"TRUE";
"B \NAC \NWC"2;
"S \NAC"
BN"3"165;
%"TAP"
"1","(-7900,5350)","2","mstr_standard","I94";
;
CDS_LIB"mstr_standard"
BODY_TYPE"PLUMBING"
HDL_TAP"TRUE";
"B \NAC \NWC"2;
"S \NAC"
BN"5"161;
%"TAP"
"1","(-7900,5300)","2","mstr_standard","I95";
;
CDS_LIB"mstr_standard"
BODY_TYPE"PLUMBING"
HDL_TAP"TRUE";
"B \NAC \NWC"2;
"S \NAC"
BN"4"163;
%"TAP"
"1","(-7900,5400)","2","mstr_standard","I96";
;
CDS_LIB"mstr_standard"
BODY_TYPE"PLUMBING"
HDL_TAP"TRUE";
"B \NAC \NWC"2;
"S \NAC"
BN"6"159;
%"TAP"
"1","(-6200,3850)","0","mstr_standard","I97";
;
CDS_LIB"mstr_standard"
BODY_TYPE"PLUMBING"
HDL_TAP"TRUE";
"B \NAC \NWC"5;
"S \NAC"
BN"0"109;
%"TAP"
"1","(-6200,3950)","0","mstr_standard","I98";
;
CDS_LIB"mstr_standard"
BODY_TYPE"PLUMBING"
HDL_TAP"TRUE";
"B \NAC \NWC"5;
"S \NAC"
BN"2"111;
%"TAP"
"1","(-6200,3900)","0","mstr_standard","I99";
;
CDS_LIB"mstr_standard"
BODY_TYPE"PLUMBING"
HDL_TAP"TRUE";
"B \NAC \NWC"5;
"S \NAC"
BN"1"110;
END.
